(kicad_pcb
	(version 20241229)
	(generator "pcbnew")
	(generator_version "9.0")
	(general
		(thickness 1.61)
		(legacy_teardrops no)
	)
	(paper "A3")
	(title_block
		(title "SO-DIMM DDR5 Tester")
		(date "2025-11-26")
		(rev "1.3.0")
		(comment 9 "footprint 59 of 627 (U4), pads 216-285 of 676")
	)
	(layers
		(0 "F.Cu" signal)
		(4 "In1.Cu" power)
		(6 "In2.Cu" mixed)
		(8 "In3.Cu" power)
		(10 "In4.Cu" mixed)
		(12 "In5.Cu" power)
		(14 "In6.Cu" mixed)
		(16 "In7.Cu" power)
		(18 "In8.Cu" power)
		(20 "In9.Cu" mixed)
		(22 "In10.Cu" power)
		(2 "B.Cu" signal)
		(9 "F.Adhes" user "F.Adhesive")
		(11 "B.Adhes" user "B.Adhesive")
		(13 "F.Paste" user)
		(15 "B.Paste" user)
		(5 "F.SilkS" user "F.Silkscreen")
		(7 "B.SilkS" user "B.Silkscreen")
		(1 "F.Mask" user)
		(3 "B.Mask" user)
		(17 "Dwgs.User" user "User.Drawings")
		(19 "Cmts.User" user "User.Comments")
		(21 "Eco1.User" user "User.Eco1")
		(23 "Eco2.User" user "User.Eco2")
		(25 "Edge.Cuts" user)
		(27 "Margin" user)
		(31 "F.CrtYd" user "F.Courtyard")
		(29 "B.CrtYd" user "B.Courtyard")
		(35 "F.Fab" user)
		(33 "B.Fab" user)
	)
	(footprint "antmicro-footprints:BGA-676_27x27mm_Layout26x26_P1x1mm_FFG676"
		(layer "F.Cu")
		(at 138.875501 174.801 180)
		(descr "FPGA XC7K160TFBG676")
		(tags "FPGA XC7K160TFBG676")
		(property "Reference" "U4"
			(at -12.224499 14.051 180)
			(layer "F.SilkS")
			(effects
				(font
					(size 0.7 0.7)
					(thickness 0.15)
				)
				(justify left bottom)
			)
		)
		(property "Value" "XC7K160T-FFG676"
			(at 0 15.5 180)
			(layer "F.Fab")
			(effects
				(font
					(size 0.7 0.7)
					(thickness 0.15)
				)
				(justify left bottom)
			)
		)
		(property "Datasheet" "https://docs.xilinx.com/v/u/en-US/ds180_7Series_Overview"
			(at 0 0 180)
			(layer "F.Fab")
			(hide yes)
			(effects
				(font
					(size 1.27 1.27)
					(thickness 0.15)
				)
			)
		)
		(property "Author" "Antmicro"
			(at 277.751002 349.602 0)
			(layer "F.Fab")
			(hide yes)
			(effects
				(font
					(size 1 1)
					(thickness 0.15)
				)
			)
		)
		(property "License" "Apache-2.0"
			(at 277.751002 349.602 0)
			(layer "F.Fab")
			(hide yes)
			(effects
				(font
					(size 1 1)
					(thickness 0.15)
				)
			)
		)
		(property "MPN" "XC7K160T-FFG676"
			(at 277.751002 349.602 0)
			(layer "F.Fab")
			(hide yes)
			(effects
				(font
					(size 1 1)
					(thickness 0.15)
				)
			)
		)
		(property "Manufacturer" "AMD-Xilinx"
			(at 277.751002 349.602 0)
			(layer "F.Fab")
			(hide yes)
			(effects
				(font
					(size 1 1)
					(thickness 0.15)
				)
			)
		)
		(sheetname "/FPGA Config/")
		(sheetfile "fpga-config.kicad_sch")
		(attr smd)
		(pad "C8" smd circle
			(at -5.5 -10.5 180)
			(size 0.5 0.5)
			(layers "F.Cu" "F.Mask" "F.Paste")
			(net 630 "/FPGA Config/FLASH.SCK")
			(pinfunction "CCLK_0")
			(pintype "bidirectional")
			(die_length 21.831)
		)
		(pad "C9" smd circle
			(at -4.5 -10.5 180)
			(size 0.5 0.5)
			(layers "F.Cu" "F.Mask" "F.Paste")
			(net 350 "/FPGA bank 16/SD.DAT2")
			(pinfunction "IO_L10P_T1_16")
			(pintype "bidirectional")
			(die_length 20.913)
		)
		(pad "C10" smd circle
			(at -3.5 -10.5 180)
			(size 0.5 0.5)
			(layers "F.Cu" "F.Mask" "F.Paste")
			(net 1 "GND")
			(pinfunction "GND")
			(pintype "passive")
		)
		(pad "C11" smd circle
			(at -2.5 -10.5 180)
			(size 0.5 0.5)
			(layers "F.Cu" "F.Mask" "F.Paste")
			(net 407 "unconnected-(U4E-IO_L13N_T2_MRCC_16-PadC11)")
			(pinfunction "IO_L13N_T2_MRCC_16")
			(pintype "bidirectional+no_connect")
			(die_length 19.377)
		)
		(pad "C12" smd circle
			(at -1.5 -10.5 180)
			(size 0.5 0.5)
			(layers "F.Cu" "F.Mask" "F.Paste")
			(net 706 "/FPGA bank 16/GCLK100")
			(pinfunction "IO_L13P_T2_MRCC_16")
			(pintype "bidirectional")
			(die_length 19.317)
		)
		(pad "C13" smd circle
			(at -0.5 -10.5 180)
			(size 0.5 0.5)
			(layers "F.Cu" "F.Mask" "F.Paste")
			(net 408 "unconnected-(U4E-IO_L19N_T3_VREF_16-PadC13)")
			(pinfunction "IO_L19N_T3_VREF_16")
			(pintype "bidirectional+no_connect")
			(die_length 16.263)
		)
		(pad "C14" smd circle
			(at 0.499 -10.5 180)
			(size 0.5 0.5)
			(layers "F.Cu" "F.Mask" "F.Paste")
			(net 409 "unconnected-(U4E-IO_L19P_T3_16-PadC14)")
			(pinfunction "IO_L19P_T3_16")
			(pintype "bidirectional+no_connect")
			(die_length 15.843)
		)
		(pad "C15" smd circle
			(at 1.499 -10.5 180)
			(size 0.5 0.5)
			(layers "F.Cu" "F.Mask" "F.Paste")
			(net 200 "+3V3")
			(pinfunction "VCCO_16")
			(pintype "passive")
		)
		(pad "C16" smd circle
			(at 2.499 -10.5 180)
			(size 0.5 0.5)
			(layers "F.Cu" "F.Mask" "F.Paste")
			(net 410 "unconnected-(U4D-IO_L1P_T0_AD0P_15-PadC16)")
			(pinfunction "IO_L1P_T0_AD0P_15")
			(pintype "bidirectional+no_connect")
			(die_length 14.788)
		)
		(pad "C17" smd circle
			(at 3.499 -10.5 180)
			(size 0.5 0.5)
			(layers "F.Cu" "F.Mask" "F.Paste")
			(net 411 "unconnected-(U4D-IO_L5P_T0_AD2P_15-PadC17)")
			(pinfunction "IO_L5P_T0_AD2P_15")
			(pintype "bidirectional+no_connect")
			(die_length 15.703)
		)
		(pad "C18" smd circle
			(at 4.499 -10.5 180)
			(size 0.5 0.5)
			(layers "F.Cu" "F.Mask" "F.Paste")
			(net 412 "unconnected-(U4D-IO_L5N_T0_AD2N_15-PadC18)")
			(pinfunction "IO_L5N_T0_AD2N_15")
			(pintype "bidirectional+no_connect")
			(die_length 17.41)
		)
		(pad "C19" smd circle
			(at 5.499 -10.5 180)
			(size 0.5 0.5)
			(layers "F.Cu" "F.Mask" "F.Paste")
			(net 413 "unconnected-(U4D-IO_L4P_T0_AD9P_15-PadC19)")
			(pinfunction "IO_L4P_T0_AD9P_15")
			(pintype "bidirectional+no_connect")
			(die_length 16.927)
		)
		(pad "C20" smd circle
			(at 6.499 -10.5 180)
			(size 0.5 0.5)
			(layers "F.Cu" "F.Mask" "F.Paste")
			(net 1 "GND")
			(pinfunction "GND")
			(pintype "passive")
		)
		(pad "C21" smd circle
			(at 7.499 -10.5 180)
			(size 0.5 0.5)
			(layers "F.Cu" "F.Mask" "F.Paste")
			(net 106 "HOT_SWAP_BUTTON")
			(pinfunction "IO_L10P_T1_D14_14")
			(pintype "bidirectional")
			(die_length 20.52)
		)
		(pad "C22" smd circle
			(at 8.499 -10.5 180)
			(size 0.5 0.5)
			(layers "F.Cu" "F.Mask" "F.Paste")
			(net 621 "/FPGA bank 14/USR_LED4")
			(pinfunction "IO_L7N_T1_D10_14")
			(pintype "bidirectional")
			(die_length 20.673)
		)
		(pad "C23" smd circle
			(at 9.499 -10.5 180)
			(size 0.5 0.5)
			(layers "F.Cu" "F.Mask" "F.Paste")
			(net 625 "/FPGA Config/FLASH.~{CS}")
			(pinfunction "IO_L6P_T0_FCS_B_14")
			(pintype "bidirectional")
			(die_length 20.723)
		)
		(pad "C24" smd circle
			(at 10.499 -10.5 180)
			(size 0.5 0.5)
			(layers "F.Cu" "F.Mask" "F.Paste")
			(net 647 "/Debug FTDI/AUX.TCK")
			(pinfunction "IO_L6N_T0_D08_VREF_14")
			(pintype "bidirectional")
			(die_length 22.056)
		)
		(pad "C25" smd circle
			(at 11.499 -10.5 180)
			(size 0.5 0.5)
			(layers "F.Cu" "F.Mask" "F.Paste")
			(net 200 "+3V3")
			(pinfunction "VCCO_14")
			(pintype "passive")
		)
		(pad "C26" smd circle
			(at 12.499 -10.5 180)
			(size 0.5 0.5)
			(layers "F.Cu" "F.Mask" "F.Paste")
			(net 651 "/Debug FTDI/AUX.TDO")
			(pinfunction "IO_L5N_T0_D07_14")
			(pintype "bidirectional")
			(die_length 24.432)
		)
		(pad "D1" smd circle
			(at -12.5 -9.5 180)
			(size 0.5 0.5)
			(layers "F.Cu" "F.Mask" "F.Paste")
			(net 27 "/FPGA MGT Interface/GTX_TX1_N")
			(pinfunction "MGTXTXN1_116")
			(pintype "bidirectional")
			(die_length 15.23)
		)
		(pad "D2" smd circle
			(at -11.5 -9.5 180)
			(size 0.5 0.5)
			(layers "F.Cu" "F.Mask" "F.Paste")
			(net 19 "/FPGA MGT Interface/GTX_TX1_P")
			(pinfunction "MGTXTXP1_116")
			(pintype "bidirectional")
			(die_length 15.219)
		)
		(pad "D3" smd circle
			(at -10.5 -9.5 180)
			(size 0.5 0.5)
			(layers "F.Cu" "F.Mask" "F.Paste")
			(net 226 "+1V2_MGTAVTT")
			(pinfunction "MGTAVTT")
			(pintype "passive")
		)
		(pad "D4" smd circle
			(at -9.5 -9.5 180)
			(size 0.5 0.5)
			(layers "F.Cu" "F.Mask" "F.Paste")
			(net 1 "GND")
			(pinfunction "GND")
			(pintype "passive")
		)
		(pad "D5" smd circle
			(at -8.5 -9.5 180)
			(size 0.5 0.5)
			(layers "F.Cu" "F.Mask" "F.Paste")
			(net 15 "/FPGA MGT Interface/GTR_REFCLK0_N")
			(pinfunction "MGTREFCLK0N_116")
			(pintype "bidirectional")
			(die_length 13.229)
		)
		(pad "D6" smd circle
			(at -7.5 -9.5 180)
			(size 0.5 0.5)
			(layers "F.Cu" "F.Mask" "F.Paste")
			(net 13 "/FPGA MGT Interface/GTR_REFCLK0_P")
			(pinfunction "MGTREFCLK0P_116")
			(pintype "bidirectional")
			(die_length 13.265)
		)
		(pad "D7" smd circle
			(at -6.5 -9.5 180)
			(size 0.5 0.5)
			(layers "F.Cu" "F.Mask" "F.Paste")
			(net 1 "GND")
			(pinfunction "GND")
			(pintype "passive")
		)
		(pad "D8" smd circle
			(at -5.5 -9.5 180)
			(size 0.5 0.5)
			(layers "F.Cu" "F.Mask" "F.Paste")
			(net 372 "/FPGA bank 16/SD.CMD")
			(pinfunction "IO_L8N_T1_16")
			(pintype "bidirectional")
			(die_length 19.972)
		)
		(pad "D9" smd circle
			(at -4.5 -9.5 180)
			(size 0.5 0.5)
			(layers "F.Cu" "F.Mask" "F.Paste")
			(net 371 "/FPGA bank 16/SD.DAT3")
			(pinfunction "IO_L8P_T1_16")
			(pintype "bidirectional")
			(die_length 18.666)
		)
		(pad "D10" smd circle
			(at -3.5 -9.5 180)
			(size 0.5 0.5)
			(layers "F.Cu" "F.Mask" "F.Paste")
			(net 373 "/FPGA bank 16/SD.CLK")
			(pinfunction "IO_L12N_T1_MRCC_16")
			(pintype "bidirectional")
			(die_length 17.142)
		)
		(pad "D11" smd circle
			(at -2.5 -9.5 180)
			(size 0.5 0.5)
			(layers "F.Cu" "F.Mask" "F.Paste")
			(net 414 "unconnected-(U4E-IO_L14N_T2_SRCC_16-PadD11)")
			(pinfunction "IO_L14N_T2_SRCC_16")
			(pintype "bidirectional+no_connect")
			(die_length 15.596)
		)
		(pad "D12" smd circle
			(at -1.5 -9.5 180)
			(size 0.5 0.5)
			(layers "F.Cu" "F.Mask" "F.Paste")
			(net 200 "+3V3")
			(pinfunction "VCCO_16")
			(pintype "passive")
		)
		(pad "D13" smd circle
			(at -0.5 -9.5 180)
			(size 0.5 0.5)
			(layers "F.Cu" "F.Mask" "F.Paste")
			(net 415 "unconnected-(U4E-IO_L17N_T2_16-PadD13)")
			(pinfunction "IO_L17N_T2_16")
			(pintype "bidirectional+no_connect")
			(die_length 16.197)
		)
		(pad "D14" smd circle
			(at 0.499 -9.5 180)
			(size 0.5 0.5)
			(layers "F.Cu" "F.Mask" "F.Paste")
			(net 416 "unconnected-(U4E-IO_L17P_T2_16-PadD14)")
			(pinfunction "IO_L17P_T2_16")
			(pintype "bidirectional+no_connect")
			(die_length 15.301)
		)
		(pad "D15" smd circle
			(at 1.499 -9.5 180)
			(size 0.5 0.5)
			(layers "F.Cu" "F.Mask" "F.Paste")
			(net 417 "unconnected-(U4D-IO_L6P_T0_15-PadD15)")
			(pinfunction "IO_L6P_T0_15")
			(pintype "bidirectional+no_connect")
			(die_length 17.491)
		)
		(pad "D16" smd circle
			(at 2.499 -9.5 180)
			(size 0.5 0.5)
			(layers "F.Cu" "F.Mask" "F.Paste")
			(net 418 "unconnected-(U4D-IO_L6N_T0_VREF_15-PadD16)")
			(pinfunction "IO_L6N_T0_VREF_15")
			(pintype "bidirectional+no_connect")
			(die_length 17.595)
		)
		(pad "D17" smd circle
			(at 3.499 -9.5 180)
			(size 0.5 0.5)
			(layers "F.Cu" "F.Mask" "F.Paste")
			(net 1 "GND")
			(pinfunction "GND")
			(pintype "passive")
		)
		(pad "D18" smd circle
			(at 4.499 -9.5 180)
			(size 0.5 0.5)
			(layers "F.Cu" "F.Mask" "F.Paste")
			(net 419 "unconnected-(U4D-IO_L13N_T2_MRCC_15-PadD18)")
			(pinfunction "IO_L13N_T2_MRCC_15")
			(pintype "bidirectional+no_connect")
			(die_length 16.746)
		)
		(pad "D19" smd circle
			(at 5.499 -9.5 180)
			(size 0.5 0.5)
			(layers "F.Cu" "F.Mask" "F.Paste")
			(net 420 "unconnected-(U4D-IO_L15P_T2_DQS_15-PadD19)")
			(pinfunction "IO_L15P_T2_DQS_15")
			(pintype "bidirectional+no_connect")
			(die_length 16.273)
		)
		(pad "D20" smd circle
			(at 6.499 -9.5 180)
			(size 0.5 0.5)
			(layers "F.Cu" "F.Mask" "F.Paste")
			(net 421 "unconnected-(U4D-IO_L15N_T2_DQS_ADV_B_15-PadD20)")
			(pinfunction "IO_L15N_T2_DQS_ADV_B_15")
			(pintype "bidirectional+no_connect")
			(die_length 16.189)
		)
		(pad "D21" smd circle
			(at 7.499 -9.5 180)
			(size 0.5 0.5)
			(layers "F.Cu" "F.Mask" "F.Paste")
			(net 615 "/FPGA bank 14/USR_LED1")
			(pinfunction "IO_L7P_T1_D09_14")
			(pintype "bidirectional")
			(die_length 20.735)
		)
		(pad "D22" smd circle
			(at 8.499 -9.5 180)
			(size 0.5 0.5)
			(layers "F.Cu" "F.Mask" "F.Paste")
			(net 200 "+3V3")
			(pinfunction "VCCO_14")
			(pintype "passive")
		)
		(pad "D23" smd circle
			(at 9.499 -9.5 180)
			(size 0.5 0.5)
			(layers "F.Cu" "F.Mask" "F.Paste")
			(net 235 "HOT_SWAP_GREEN")
			(pinfunction "IO_L11P_T1_SRCC_14")
			(pintype "bidirectional")
			(die_length 20.085)
		)
		(pad "D24" smd circle
			(at 10.499 -9.5 180)
			(size 0.5 0.5)
			(layers "F.Cu" "F.Mask" "F.Paste")
			(net 649 "/Debug FTDI/AUX.TDI")
			(pinfunction "IO_L11N_T1_SRCC_14")
			(pintype "bidirectional")
			(die_length 20.314)
		)
		(pad "D25" smd circle
			(at 11.499 -9.5 180)
			(size 0.5 0.5)
			(layers "F.Cu" "F.Mask" "F.Paste")
			(net 653 "/Debug FTDI/AUX.TMS")
			(pinfunction "IO_L15N_T2_DQS_DOUT_CSO_B_14")
			(pintype "bidirectional")
			(die_length 20.821)
		)
		(pad "D26" smd circle
			(at 12.499 -9.5 180)
			(size 0.5 0.5)
			(layers "F.Cu" "F.Mask" "F.Paste")
			(net 683 "/FPGA bank 14/FPGA_DDR.SDA")
			(pinfunction "IO_L5P_T0_D06_14")
			(pintype "bidirectional")
			(die_length 24.394)
		)
		(pad "E1" smd circle
			(at -12.5 -8.5 180)
			(size 0.5 0.5)
			(layers "F.Cu" "F.Mask" "F.Paste")
			(net 1 "GND")
			(pinfunction "GND")
			(pintype "passive")
		)
		(pad "E2" smd circle
			(at -11.5 -8.5 180)
			(size 0.5 0.5)
			(layers "F.Cu" "F.Mask" "F.Paste")
			(net 1 "GND")
			(pinfunction "GND")
			(pintype "passive")
		)
		(pad "E3" smd circle
			(at -10.5 -8.5 180)
			(size 0.5 0.5)
			(layers "F.Cu" "F.Mask" "F.Paste")
			(net 609 "/FPGA MGT Interface/PCIE.RXD2_N")
			(pinfunction "MGTXRXN1_116")
			(pintype "bidirectional")
			(die_length 13.353)
		)
		(pad "E4" smd circle
			(at -9.5 -8.5 180)
			(size 0.5 0.5)
			(layers "F.Cu" "F.Mask" "F.Paste")
			(net 608 "/FPGA MGT Interface/PCIE.RXD2_P")
			(pinfunction "MGTXRXP1_116")
			(pintype "bidirectional")
			(die_length 13.435)
		)
		(pad "E5" smd circle
			(at -8.5 -8.5 180)
			(size 0.5 0.5)
			(layers "F.Cu" "F.Mask" "F.Paste")
			(net 1 "GND")
			(pinfunction "GND")
			(pintype "passive")
		)
		(pad "E6" smd circle
			(at -7.5 -8.5 180)
			(size 0.5 0.5)
			(layers "F.Cu" "F.Mask" "F.Paste")
			(net 187 "+1V0_MGTAVCC")
			(pinfunction "MGTAVCC")
			(pintype "passive")
		)
		(pad "E7" smd circle
			(at -6.5 -8.5 180)
			(size 0.5 0.5)
			(layers "F.Cu" "F.Mask" "F.Paste")
			(net 1 "GND")
			(pinfunction "GND")
			(pintype "passive")
		)
		(pad "E8" smd circle
			(at -5.5 -8.5 180)
			(size 0.5 0.5)
			(layers "F.Cu" "F.Mask" "F.Paste")
			(net 188 "+1V8")
			(pinfunction "VCCBATT_0")
			(pintype "power_in")
		)
		(pad "E9" smd circle
			(at -4.5 -8.5 180)
			(size 0.5 0.5)
			(layers "F.Cu" "F.Mask" "F.Paste")
			(net 200 "+3V3")
			(pinfunction "VCCO_16")
			(pintype "passive")
		)
		(pad "E10" smd circle
			(at -3.5 -8.5 180)
			(size 0.5 0.5)
			(layers "F.Cu" "F.Mask" "F.Paste")
			(net 374 "/FPGA bank 16/SD.DAT0")
			(pinfunction "IO_L12P_T1_MRCC_16")
			(pintype "bidirectional")
			(die_length 17.165)
		)
		(pad "E11" smd circle
			(at -2.5 -8.5 180)
			(size 0.5 0.5)
			(layers "F.Cu" "F.Mask" "F.Paste")
			(net 422 "unconnected-(U4E-IO_L14P_T2_SRCC_16-PadE11)")
			(pinfunction "IO_L14P_T2_SRCC_16")
			(pintype "bidirectional+no_connect")
			(die_length 15.195)
		)
		(pad "E12" smd circle
			(at -1.5 -8.5 180)
			(size 0.5 0.5)
			(layers "F.Cu" "F.Mask" "F.Paste")
			(net 423 "unconnected-(U4E-IO_L18N_T2_16-PadE12)")
			(pinfunction "IO_L18N_T2_16")
			(pintype "bidirectional+no_connect")
			(die_length 14.446)
		)
		(pad "E13" smd circle
			(at -0.5 -8.5 180)
			(size 0.5 0.5)
			(layers "F.Cu" "F.Mask" "F.Paste")
			(net 424 "unconnected-(U4E-IO_L18P_T2_16-PadE13)")
			(pinfunction "IO_L18P_T2_16")
			(pintype "bidirectional+no_connect")
			(die_length 14.156)
		)
		(pad "E14" smd circle
			(at 0.499 -8.5 180)
			(size 0.5 0.5)
			(layers "F.Cu" "F.Mask" "F.Paste")
			(net 1 "GND")
			(pinfunction "GND")
			(pintype "passive")
		)
		(pad "E15" smd circle
			(at 1.499 -8.5 180)
			(size 0.5 0.5)
			(layers "F.Cu" "F.Mask" "F.Paste")
			(net 425 "unconnected-(U4D-IO_L10P_T1_AD4P_15-PadE15)")
			(pinfunction "IO_L10P_T1_AD4P_15")
			(pintype "bidirectional+no_connect")
			(die_length 18.592)
		)
		(pad "E16" smd circle
			(at 2.499 -8.5 180)
			(size 0.5 0.5)
			(layers "F.Cu" "F.Mask" "F.Paste")
			(net 426 "unconnected-(U4D-IO_L10N_T1_AD4N_15-PadE16)")
			(pinfunction "IO_L10N_T1_AD4N_15")
			(pintype "bidirectional+no_connect")
			(die_length 18.741)
		)
		(pad "E17" smd circle
			(at 3.499 -8.5 180)
			(size 0.5 0.5)
			(layers "F.Cu" "F.Mask" "F.Paste")
			(net 427 "unconnected-(U4D-IO_L12N_T1_MRCC_AD5N_15-PadE17)")
			(pinfunction "IO_L12N_T1_MRCC_AD5N_15")
			(pintype "bidirectional+no_connect")
			(die_length 14.038)
		)
		(pad "E18" smd circle
			(at 4.499 -8.5 180)
			(size 0.5 0.5)
			(layers "F.Cu" "F.Mask" "F.Paste")
			(net 428 "unconnected-(U4D-IO_L13P_T2_MRCC_15-PadE18)")
			(pinfunction "IO_L13P_T2_MRCC_15")
			(pintype "bidirectional+no_connect")
			(die_length 17.01)
		)
		(pad "E19" smd circle
			(at 5.499 -8.5 180)
			(size 0.5 0.5)
			(layers "F.Cu" "F.Mask" "F.Paste")
			(net 377 "Net-(R97-Pad2)")
			(pinfunction "VCCO_15")
			(pintype "passive")
		)
		(pad "E20" smd circle
			(at 6.499 -8.5 180)
			(size 0.5 0.5)
			(layers "F.Cu" "F.Mask" "F.Paste")
			(net 429 "unconnected-(U4D-IO_L17N_T2_A25_15-PadE20)")
			(pinfunction "IO_L17N_T2_A25_15")
			(pintype "bidirectional+no_connect")
			(die_length 13.703)
		)
		(pad "E21" smd circle
			(at 7.499 -8.5 180)
			(size 0.5 0.5)
			(layers "F.Cu" "F.Mask" "F.Paste")
			(net 236 "HOT_SWAP_RED")
			(pinfunction "IO_L9P_T1_DQS_14")
			(pintype "bidirectional")
			(die_length 20.497)
		)
		(pad "E22" smd circle
			(at 8.499 -8.5 180)
			(size 0.5 0.5)
			(layers "F.Cu" "F.Mask" "F.Paste")
			(net 622 "/FPGA bank 14/USR_LED5")
			(pinfunction "IO_L9N_T1_DQS_D13_14")
			(pintype "bidirectional")
			(die_length 20.469)
		)
		(pad "E23" smd circle
			(at 9.499 -8.5 180)
			(size 0.5 0.5)
			(layers "F.Cu" "F.Mask" "F.Paste")
			(net 430 "unconnected-(U4C-IO_L12N_T1_MRCC_14-PadE23)")
			(pinfunction "IO_L12N_T1_MRCC_14")
			(pintype "bidirectional+no_connect")
			(die_length 19.664)
		)
		(pad "E24" smd circle
			(at 10.499 -8.5 180)
			(size 0.5 0.5)
			(layers "F.Cu" "F.Mask" "F.Paste")
			(net 1 "GND")
			(pinfunction "GND")
			(pintype "passive")
		)
		(pad "E25" smd circle
			(at 11.499 -8.5 180)
			(size 0.5 0.5)
			(layers "F.Cu" "F.Mask" "F.Paste")
			(net 682 "/FPGA bank 14/FPGA_DDR.SCL")
			(pinfunction "IO_L15P_T2_DQS_RDWR_B_14")
			(pintype "bidirectional")
			(die_length 20.423)
		)
	)
)
